(kicad_pcb
	(version 20260206)
	(generator "pcbnew")
	(generator_version "10.0")
	(general
		(thickness 1.6)
		(legacy_teardrops no)
	)
	(paper "A4")
	(title_block
		(title "03242023_DA0F0TMBIJ0_F0T_Motherboard_J_brd_V01_OCP.brd")
		(comment 1 "Grand Teton / footprints 4373-4377 of 6105")
	)
	(layers
		(0 "F.Cu" signal "TOP")
		(4 "In1.Cu" signal "GND")
		(6 "In2.Cu" signal "IN1")
		(8 "In3.Cu" signal "GND1")
		(10 "In4.Cu" signal "IN2")
		(12 "In5.Cu" signal "GND2")
		(14 "In6.Cu" signal "IN3")
		(16 "In7.Cu" signal "GND3")
		(18 "In8.Cu" signal "VCC")
		(20 "In9.Cu" signal "VCC1")
		(22 "In10.Cu" signal "GND4")
		(24 "In11.Cu" signal "IN4")
		(26 "In12.Cu" signal "GND5")
		(28 "In13.Cu" signal "IN5")
		(30 "In14.Cu" signal "GND6")
		(32 "In15.Cu" signal "IN6")
		(34 "In16.Cu" signal "GND7")
		(2 "B.Cu" signal "BOTTOM")
		(9 "F.Adhes" user "F.Adhesive")
		(11 "B.Adhes" user "B.Adhesive")
		(13 "F.Paste" user "Package Geometry/Pastemask Top")
		(15 "B.Paste" user "Package Geometry/Pastemask Bottom")
		(5 "F.SilkS" user "Ref Des/Silkscreen Top")
		(7 "B.SilkS" user "Ref Des/Silkscreen Bottom")
		(1 "F.Mask" user "Board Geometry/Soldermask Top")
		(3 "B.Mask" user "Board Geometry/Soldermask Bottom")
		(17 "Dwgs.User" user "User.Drawings")
		(19 "Cmts.User" user "User.Comments")
		(21 "Eco1.User" user "User.Eco1")
		(23 "Eco2.User" user "User.Eco2")
		(25 "Edge.Cuts" user "Board Geometry/Outline")
		(27 "Margin" user)
		(31 "F.CrtYd" user "Package Geometry/Place Bound Top")
		(29 "B.CrtYd" user "Package Geometry/Place Bound Bottom")
		(35 "F.Fab" user "Ref Des/Assembly Top")
		(33 "B.Fab" user "Ref Des/Assembly Bottom")
	)
	(footprint ""
		(layer "B.Cu")
		(at 452.028814 -319.263776 180)
		(property "Reference" "C47"
			(at 0 0 0)
			(layer "B.SilkS")
			(hide yes)
			(effects
				(font
					(size 1.27 1.27)
				)
				(justify mirror)
			)
		)
		(property "Value" ""
			(at 0 0 0)
			(layer "B.Fab")
			(effects
				(font
					(size 1.27 1.27)
				)
				(justify mirror)
			)
		)
		(duplicate_pad_numbers_are_jumpers no)
		(fp_line
			(start 0.7874 0.4064)
			(end 0.7874 -0.4064)
			(stroke
				(width 0.1524)
				(type default)
			)
			(layer "B.SilkS")
		)
		(fp_line
			(start 0.7874 -0.4064)
			(end -0.7874 -0.4064)
			(stroke
				(width 0.1524)
				(type default)
			)
			(layer "B.SilkS")
		)
		(fp_line
			(start -0.7874 0.4064)
			(end 0.7874 0.4064)
			(stroke
				(width 0.1524)
				(type default)
			)
			(layer "B.SilkS")
		)
		(fp_line
			(start -0.7874 -0.4064)
			(end -0.7874 0.4064)
			(stroke
				(width 0.1524)
				(type default)
			)
			(layer "B.SilkS")
		)
		(fp_line
			(start 0.67945 0.3048)
			(end 0.67945 -0.305054)
			(stroke
				(width 0.1)
				(type default)
			)
			(layer "B.Fab")
		)
		(fp_line
			(start 0.67945 -0.305054)
			(end 0.12065 -0.305054)
			(stroke
				(width 0.1)
				(type default)
			)
			(layer "B.Fab")
		)
		(fp_line
			(start 0.12065 0.3048)
			(end 0.67945 0.3048)
			(stroke
				(width 0.1)
				(type default)
			)
			(layer "B.Fab")
		)
		(fp_line
			(start 0.12065 0.2794)
			(end 0.12065 0.3048)
			(stroke
				(width 0.1)
				(type default)
			)
			(layer "B.Fab")
		)
		(fp_line
			(start 0.12065 -0.2794)
			(end -0.12065 -0.2794)
			(stroke
				(width 0.1)
				(type default)
			)
			(layer "B.Fab")
		)
		(fp_line
			(start 0.12065 -0.305054)
			(end 0.12065 -0.2794)
			(stroke
				(width 0.1)
				(type default)
			)
			(layer "B.Fab")
		)
		(fp_line
			(start -0.120396 0.3048)
			(end -0.120396 0.2794)
			(stroke
				(width 0.1)
				(type default)
			)
			(layer "B.Fab")
		)
		(fp_line
			(start -0.120396 0.2794)
			(end 0.12065 0.2794)
			(stroke
				(width 0.1)
				(type default)
			)
			(layer "B.Fab")
		)
		(fp_line
			(start -0.12065 -0.2794)
			(end -0.12065 -0.3048)
			(stroke
				(width 0.1)
				(type default)
			)
			(layer "B.Fab")
		)
		(fp_line
			(start -0.12065 -0.3048)
			(end -0.67945 -0.3048)
			(stroke
				(width 0.1)
				(type default)
			)
			(layer "B.Fab")
		)
		(fp_line
			(start -0.67945 0.3048)
			(end -0.120396 0.3048)
			(stroke
				(width 0.1)
				(type default)
			)
			(layer "B.Fab")
		)
		(fp_line
			(start -0.67945 -0.3048)
			(end -0.67945 0.3048)
			(stroke
				(width 0.1)
				(type default)
			)
			(layer "B.Fab")
		)
		(pad "1" smd circle
			(at 0.40005 0)
			(size 0 0)
			(layers "B.Cu" "B.Mask" "B.Paste")
			(net "P3V3_AUX")
		)
		(pad "2" smd circle
			(at -0.40005 0)
			(size 0 0)
			(layers "B.Cu" "B.Mask" "B.Paste")
			(net "GND")
		)
	)
	(footprint ""
		(layer "B.Cu")
		(at 339.58022 -31.929578 90)
		(property "Reference" "R1311"
			(at 0 0 90)
			(layer "B.SilkS")
			(hide yes)
			(effects
				(font
					(size 1.27 1.27)
				)
				(justify mirror)
			)
		)
		(property "Value" ""
			(at 0 0 90)
			(layer "B.Fab")
			(effects
				(font
					(size 1.27 1.27)
				)
				(justify mirror)
			)
		)
		(duplicate_pad_numbers_are_jumpers no)
		(fp_line
			(start 0.7874 -0.4064)
			(end -0.7874 -0.4064)
			(stroke
				(width 0.1524)
				(type default)
			)
			(layer "B.SilkS")
		)
		(fp_line
			(start -0.7874 -0.4064)
			(end -0.7874 0.4064)
			(stroke
				(width 0.1524)
				(type default)
			)
			(layer "B.SilkS")
		)
		(fp_line
			(start 0.7874 0.4064)
			(end 0.7874 -0.4064)
			(stroke
				(width 0.1524)
				(type default)
			)
			(layer "B.SilkS")
		)
		(fp_line
			(start -0.7874 0.4064)
			(end 0.7874 0.4064)
			(stroke
				(width 0.1524)
				(type default)
			)
			(layer "B.SilkS")
		)
		(fp_line
			(start 0.67945 -0.305054)
			(end 0.12065 -0.305054)
			(stroke
				(width 0.1)
				(type default)
			)
			(layer "B.Fab")
		)
		(fp_line
			(start 0.12065 -0.305054)
			(end 0.12065 -0.2794)
			(stroke
				(width 0.1)
				(type default)
			)
			(layer "B.Fab")
		)
		(fp_line
			(start -0.12065 -0.3048)
			(end -0.67945 -0.3048)
			(stroke
				(width 0.1)
				(type default)
			)
			(layer "B.Fab")
		)
		(fp_line
			(start -0.67945 -0.3048)
			(end -0.67945 0.3048)
			(stroke
				(width 0.1)
				(type default)
			)
			(layer "B.Fab")
		)
		(fp_line
			(start 0.12065 -0.2794)
			(end -0.12065 -0.2794)
			(stroke
				(width 0.1)
				(type default)
			)
			(layer "B.Fab")
		)
		(fp_line
			(start -0.12065 -0.2794)
			(end -0.12065 -0.3048)
			(stroke
				(width 0.1)
				(type default)
			)
			(layer "B.Fab")
		)
		(fp_line
			(start 0.12065 0.2794)
			(end 0.12065 0.3048)
			(stroke
				(width 0.1)
				(type default)
			)
			(layer "B.Fab")
		)
		(fp_line
			(start -0.120396 0.2794)
			(end 0.12065 0.2794)
			(stroke
				(width 0.1)
				(type default)
			)
			(layer "B.Fab")
		)
		(fp_line
			(start 0.67945 0.3048)
			(end 0.67945 -0.305054)
			(stroke
				(width 0.1)
				(type default)
			)
			(layer "B.Fab")
		)
		(fp_line
			(start 0.12065 0.3048)
			(end 0.67945 0.3048)
			(stroke
				(width 0.1)
				(type default)
			)
			(layer "B.Fab")
		)
		(fp_line
			(start -0.120396 0.3048)
			(end -0.120396 0.2794)
			(stroke
				(width 0.1)
				(type default)
			)
			(layer "B.Fab")
		)
		(fp_line
			(start -0.67945 0.3048)
			(end -0.120396 0.3048)
			(stroke
				(width 0.1)
				(type default)
			)
			(layer "B.Fab")
		)
		(pad "1" smd circle
			(at 0.40005 0 270)
			(size 0 0)
			(layers "B.Cu" "B.Mask" "B.Paste")
			(net "FM_XTAL_INPUT_FREQUENCY_0_MGPIO")
		)
		(pad "2" smd circle
			(at -0.40005 0 270)
			(size 0 0)
			(layers "B.Cu" "B.Mask" "B.Paste")
			(net "GND")
		)
	)
	(footprint ""
		(layer "B.Cu")
		(at 127.7874 -21.003768 90)
		(property "Reference" "R4288"
			(at 0 0 90)
			(layer "B.SilkS")
			(hide yes)
			(effects
				(font
					(size 1.27 1.27)
				)
				(justify mirror)
			)
		)
		(property "Value" ""
			(at 0 0 90)
			(layer "B.Fab")
			(effects
				(font
					(size 1.27 1.27)
				)
				(justify mirror)
			)
		)
		(duplicate_pad_numbers_are_jumpers no)
		(fp_line
			(start 0.7874 -0.4064)
			(end -0.7874 -0.4064)
			(stroke
				(width 0.1524)
				(type default)
			)
			(layer "B.SilkS")
		)
		(fp_line
			(start -0.7874 -0.4064)
			(end -0.7874 0.4064)
			(stroke
				(width 0.1524)
				(type default)
			)
			(layer "B.SilkS")
		)
		(fp_line
			(start 0.7874 0.4064)
			(end 0.7874 -0.4064)
			(stroke
				(width 0.1524)
				(type default)
			)
			(layer "B.SilkS")
		)
		(fp_line
			(start -0.7874 0.4064)
			(end 0.7874 0.4064)
			(stroke
				(width 0.1524)
				(type default)
			)
			(layer "B.SilkS")
		)
		(fp_line
			(start 0.67945 -0.305054)
			(end 0.12065 -0.305054)
			(stroke
				(width 0.1)
				(type default)
			)
			(layer "B.Fab")
		)
		(fp_line
			(start 0.12065 -0.305054)
			(end 0.12065 -0.2794)
			(stroke
				(width 0.1)
				(type default)
			)
			(layer "B.Fab")
		)
		(fp_line
			(start -0.12065 -0.3048)
			(end -0.67945 -0.3048)
			(stroke
				(width 0.1)
				(type default)
			)
			(layer "B.Fab")
		)
		(fp_line
			(start -0.67945 -0.3048)
			(end -0.67945 0.3048)
			(stroke
				(width 0.1)
				(type default)
			)
			(layer "B.Fab")
		)
		(fp_line
			(start 0.12065 -0.2794)
			(end -0.12065 -0.2794)
			(stroke
				(width 0.1)
				(type default)
			)
			(layer "B.Fab")
		)
		(fp_line
			(start -0.12065 -0.2794)
			(end -0.12065 -0.3048)
			(stroke
				(width 0.1)
				(type default)
			)
			(layer "B.Fab")
		)
		(fp_line
			(start 0.12065 0.2794)
			(end 0.12065 0.3048)
			(stroke
				(width 0.1)
				(type default)
			)
			(layer "B.Fab")
		)
		(fp_line
			(start -0.120396 0.2794)
			(end 0.12065 0.2794)
			(stroke
				(width 0.1)
				(type default)
			)
			(layer "B.Fab")
		)
		(fp_line
			(start 0.67945 0.3048)
			(end 0.67945 -0.305054)
			(stroke
				(width 0.1)
				(type default)
			)
			(layer "B.Fab")
		)
		(fp_line
			(start 0.12065 0.3048)
			(end 0.67945 0.3048)
			(stroke
				(width 0.1)
				(type default)
			)
			(layer "B.Fab")
		)
		(fp_line
			(start -0.120396 0.3048)
			(end -0.120396 0.2794)
			(stroke
				(width 0.1)
				(type default)
			)
			(layer "B.Fab")
		)
		(fp_line
			(start -0.67945 0.3048)
			(end -0.120396 0.3048)
			(stroke
				(width 0.1)
				(type default)
			)
			(layer "B.Fab")
		)
		(pad "1" smd circle
			(at 0.40005 0 270)
			(size 0 0)
			(layers "B.Cu" "B.Mask" "B.Paste")
			(net "FM_USB3_1_SWA")
		)
		(pad "2" smd circle
			(at -0.40005 0 270)
			(size 0 0)
			(layers "B.Cu" "B.Mask" "B.Paste")
			(net "GND")
		)
	)
	(footprint ""
		(layer "B.Cu")
		(at 324.98919 -28.45435 90)
		(property "Reference" "R614"
			(at 0 0 90)
			(layer "B.SilkS")
			(hide yes)
			(effects
				(font
					(size 1.27 1.27)
				)
				(justify mirror)
			)
		)
		(property "Value" ""
			(at 0 0 90)
			(layer "B.Fab")
			(effects
				(font
					(size 1.27 1.27)
				)
				(justify mirror)
			)
		)
		(duplicate_pad_numbers_are_jumpers no)
		(fp_line
			(start 0.7874 -0.4064)
			(end -0.7874 -0.4064)
			(stroke
				(width 0.1524)
				(type default)
			)
			(layer "B.SilkS")
		)
		(fp_line
			(start -0.7874 -0.4064)
			(end -0.7874 0.4064)
			(stroke
				(width 0.1524)
				(type default)
			)
			(layer "B.SilkS")
		)
		(fp_line
			(start 0.7874 0.4064)
			(end 0.7874 -0.4064)
			(stroke
				(width 0.1524)
				(type default)
			)
			(layer "B.SilkS")
		)
		(fp_line
			(start -0.7874 0.4064)
			(end 0.7874 0.4064)
			(stroke
				(width 0.1524)
				(type default)
			)
			(layer "B.SilkS")
		)
		(fp_line
			(start 0.67945 -0.305054)
			(end 0.12065 -0.305054)
			(stroke
				(width 0.1)
				(type default)
			)
			(layer "B.Fab")
		)
		(fp_line
			(start 0.12065 -0.305054)
			(end 0.12065 -0.2794)
			(stroke
				(width 0.1)
				(type default)
			)
			(layer "B.Fab")
		)
		(fp_line
			(start -0.12065 -0.3048)
			(end -0.67945 -0.3048)
			(stroke
				(width 0.1)
				(type default)
			)
			(layer "B.Fab")
		)
		(fp_line
			(start -0.67945 -0.3048)
			(end -0.67945 0.3048)
			(stroke
				(width 0.1)
				(type default)
			)
			(layer "B.Fab")
		)
		(fp_line
			(start 0.12065 -0.2794)
			(end -0.12065 -0.2794)
			(stroke
				(width 0.1)
				(type default)
			)
			(layer "B.Fab")
		)
		(fp_line
			(start -0.12065 -0.2794)
			(end -0.12065 -0.3048)
			(stroke
				(width 0.1)
				(type default)
			)
			(layer "B.Fab")
		)
		(fp_line
			(start 0.12065 0.2794)
			(end 0.12065 0.3048)
			(stroke
				(width 0.1)
				(type default)
			)
			(layer "B.Fab")
		)
		(fp_line
			(start -0.120396 0.2794)
			(end 0.12065 0.2794)
			(stroke
				(width 0.1)
				(type default)
			)
			(layer "B.Fab")
		)
		(fp_line
			(start 0.67945 0.3048)
			(end 0.67945 -0.305054)
			(stroke
				(width 0.1)
				(type default)
			)
			(layer "B.Fab")
		)
		(fp_line
			(start 0.12065 0.3048)
			(end 0.67945 0.3048)
			(stroke
				(width 0.1)
				(type default)
			)
			(layer "B.Fab")
		)
		(fp_line
			(start -0.120396 0.3048)
			(end -0.120396 0.2794)
			(stroke
				(width 0.1)
				(type default)
			)
			(layer "B.Fab")
		)
		(fp_line
			(start -0.67945 0.3048)
			(end -0.120396 0.3048)
			(stroke
				(width 0.1)
				(type default)
			)
			(layer "B.Fab")
		)
		(pad "1" smd circle
			(at 0.40005 0 270)
			(size 0 0)
			(layers "B.Cu" "B.Mask" "B.Paste")
			(net "FM_JTAG_ODT_DISABLE")
		)
		(pad "2" smd circle
			(at -0.40005 0 270)
			(size 0 0)
			(layers "B.Cu" "B.Mask" "B.Paste")
			(net "GND")
		)
	)
	(footprint ""
		(layer "B.Cu")
		(at 211.836 -70.852792 180)
		(property "Reference" "U68"
			(at -0.51562 -3.679698 0)
			(unlocked yes)
			(layer "B.SilkS")
			(effects
				(font
					(size 0.7874 0.5842)
					(thickness 0.1524)
				)
				(justify left mirror)
			)
		)
		(property "Value" ""
			(at 0 0 0)
			(layer "B.Fab")
			(effects
				(font
					(size 1.27 1.27)
				)
				(justify mirror)
			)
		)
		(duplicate_pad_numbers_are_jumpers no)
		(fp_line
			(start 2.0066 2.5527)
			(end 2.0066 -2.5527)
			(stroke
				(width 0.1524)
				(type default)
			)
			(layer "B.SilkS")
		)
		(fp_line
			(start 2.0066 -2.5527)
			(end 0.5715 -2.5527)
			(stroke
				(width 0.1524)
				(type default)
			)
			(layer "B.SilkS")
		)
		(fp_line
			(start 0.5715 -2.5527)
			(end 0 -1.9812)
			(stroke
				(width 0.1524)
				(type default)
			)
			(layer "B.SilkS")
		)
		(fp_line
			(start 0 -1.9812)
			(end -0.5715 -2.5527)
			(stroke
				(width 0.1524)
				(type default)
			)
			(layer "B.SilkS")
		)
		(fp_line
			(start -0.5715 -2.5527)
			(end -2.0066 -2.5527)
			(stroke
				(width 0.1524)
				(type default)
			)
			(layer "B.SilkS")
		)
		(fp_line
			(start -2.0066 2.5527)
			(end 2.0066 2.5527)
			(stroke
				(width 0.1524)
				(type default)
			)
			(layer "B.SilkS")
		)
		(fp_line
			(start -2.0066 -2.5527)
			(end -2.0066 2.5527)
			(stroke
				(width 0.1524)
				(type default)
			)
			(layer "B.SilkS")
		)
		(fp_poly
			(pts
				(xy 3.81 -1.905) (xy 4.36372 -2.233168) (xy 4.36372 -1.608328)
			)
			(stroke
				(width 0)
				(type default)
			)
			(fill yes)
			(layer "B.SilkS")
		)
		(fp_line
			(start 2.249932 2.549906)
			(end 2.249932 -2.549906)
			(stroke
				(width 0.1)
				(type default)
			)
			(layer "B.Fab")
		)
		(fp_line
			(start 2.249932 -2.549906)
			(end -2.249932 -2.549906)
			(stroke
				(width 0.1)
				(type default)
			)
			(layer "B.Fab")
		)
		(fp_line
			(start -2.249932 2.549906)
			(end 2.249932 2.549906)
			(stroke
				(width 0.1)
				(type default)
			)
			(layer "B.Fab")
		)
		(fp_line
			(start -2.249932 -2.549906)
			(end -2.249932 2.549906)
			(stroke
				(width 0.1)
				(type default)
			)
			(layer "B.Fab")
		)
		(fp_poly
			(pts
				(xy 4.36372 -1.608328) (xy 4.36372 -2.233168) (xy 3.81 -1.905)
			)
			(stroke
				(width 0)
				(type default)
			)
			(fill yes)
			(layer "B.Fab")
		)
		(pad "1" smd rect
			(at 2.921 -1.949958 90)
			(size 0.3556 1.4986)
			(layers "B.Cu" "B.Mask" "B.Paste")
			(net "FB_BMC_ISOLATE")
		)
		(pad "2" smd rect
			(at 2.921 -1.299972 90)
			(size 0.3556 1.4986)
			(layers "B.Cu" "B.Mask" "B.Paste")
			(net "NCSI_BMC_TXD1_R")
		)
		(pad "3" smd rect
			(at 2.921 -0.649986 90)
			(size 0.3556 1.4986)
			(layers "B.Cu" "B.Mask" "B.Paste")
			(net "NCSI_OCP_SFF_TXD1")
		)
		(pad "4" smd rect
			(at 2.921 0 90)
			(size 0.3556 1.4986)
			(layers "B.Cu" "B.Mask" "B.Paste")
			(net "FB_BMC_ISOLATE")
		)
		(pad "5" smd rect
			(at 2.921 0.649986 90)
			(size 0.3556 1.4986)
			(layers "B.Cu" "B.Mask" "B.Paste")
			(net "NCSI_BMC_TXD0_R")
		)
		(pad "6" smd rect
			(at 2.921 1.299972 90)
			(size 0.3556 1.4986)
			(layers "B.Cu" "B.Mask" "B.Paste")
			(net "NCSI_OCP_SFF_TXD0")
		)
		(pad "7" smd rect
			(at 2.921 1.949958 90)
			(size 0.3556 1.4986)
			(layers "B.Cu" "B.Mask" "B.Paste")
			(net "GND")
		)
		(pad "8" smd rect
			(at -2.921 1.949958 90)
			(size 0.3556 1.4986)
			(layers "B.Cu" "B.Mask" "B.Paste")
			(net "NCSI_OCP_SFF_TX_EN")
		)
		(pad "9" smd rect
			(at -2.921 1.299972 90)
			(size 0.3556 1.4986)
			(layers "B.Cu" "B.Mask" "B.Paste")
			(net "NCSI_BMC_TX_EN_R")
		)
		(pad "10" smd rect
			(at -2.921 0.649986 90)
			(size 0.3556 1.4986)
			(layers "B.Cu" "B.Mask" "B.Paste")
			(net "FB_BMC_ISOLATE")
		)
		(pad "11" smd rect
			(at -2.921 0 90)
			(size 0.3556 1.4986)
			(layers "B.Cu" "B.Mask" "B.Paste")
			(net "OCP_SFF_ISO2_RBT_ARB_OUT")
		)
		(pad "12" smd rect
			(at -2.921 -0.649986 90)
			(size 0.3556 1.4986)
			(layers "B.Cu" "B.Mask" "B.Paste")
			(net "OCP_SFF_RBT_ARB_OUT")
		)
		(pad "13" smd rect
			(at -2.921 -1.299972 90)
			(size 0.3556 1.4986)
			(layers "B.Cu" "B.Mask" "B.Paste")
			(net "FB_BMC_ISOLATE")
		)
		(pad "14" smd rect
			(at -2.921 -1.949958 90)
			(size 0.3556 1.4986)
			(layers "B.Cu" "B.Mask" "B.Paste")
			(net "P3V3_AUX")
		)
	)
)
